# T6G (Grand Teton) — schematic netlist excerpt (pin names and nets, part order shuffled) for the footprints in the layout excerpt that follows; sources: Cadence DE-HDL packaged netlist, KiCad conversion of 04192023_DAF0TMB3IC0_F0TG_MB_C_brd_V02_OCP.brd

R36  Q_RES  10K 1% CHIP  pkg 0402LF  page 98 : A = PD_CHA_CPU1_DIMM0_SAA ; B = GND
C21  Q_CAP  0.1UF 25V 10% X7R  pkg 0402  page 131 : A = P12V_OCP_SFF_R ; B = GND
R1211  Q_RES  0 5% CHIP  pkg 0201LF  page 186 : A = RST_SMB_RT_ROM_R1_N ; B = FM_SMB_RT_ROM_MUX5_SEL

(kicad_pcb
	(version 20260206)
	(generator "pcbnew")
	(generator_version "10.0")
	(general
		(thickness 1.6)
		(legacy_teardrops no)
	)
	(paper "A4")
	(title_block
		(title "04192023_DAF0TMB3IC0_F0TG_MB_C_brd_V02_OCP.brd")
		(comment 1 "Grand Teton / footprints 7665-7667 of 8354")
	)
	(layers
		(0 "F.Cu" signal "TOP")
		(4 "In1.Cu" signal "GND")
		(6 "In2.Cu" signal "IN1")
		(8 "In3.Cu" signal "GND1")
		(10 "In4.Cu" signal "IN2")
		(12 "In5.Cu" signal "GND2")
		(14 "In6.Cu" signal "IN3")
		(16 "In7.Cu" signal "GND3")
		(18 "In8.Cu" signal "VCC")
		(20 "In9.Cu" signal "VCC1")
		(22 "In10.Cu" signal "GND4")
		(24 "In11.Cu" signal "IN4")
		(26 "In12.Cu" signal "GND5")
		(28 "In13.Cu" signal "IN5")
		(30 "In14.Cu" signal "GND6")
		(32 "In15.Cu" signal "IN6")
		(34 "In16.Cu" signal "GND7")
		(2 "B.Cu" signal "BOTTOM")
		(9 "F.Adhes" user "F.Adhesive")
		(11 "B.Adhes" user "B.Adhesive")
		(13 "F.Paste" user "Package Geometry/Pastemask Top")
		(15 "B.Paste" user "Package Geometry/Pastemask Bottom")
		(5 "F.SilkS" user "Ref Des/Silkscreen Top")
		(7 "B.SilkS" user "Ref Des/Silkscreen Bottom")
		(1 "F.Mask" user "Board Geometry/Soldermask Top")
		(3 "B.Mask" user "Board Geometry/Soldermask Bottom")
		(17 "Dwgs.User" user "User.Drawings")
		(19 "Cmts.User" user "User.Comments")
		(21 "Eco1.User" user "User.Eco1")
		(23 "Eco2.User" user "User.Eco2")
		(25 "Edge.Cuts" user "Board Geometry/Outline")
		(27 "Margin" user)
		(31 "F.CrtYd" user "Package Geometry/Place Bound Top")
		(29 "B.CrtYd" user "Package Geometry/Place Bound Bottom")
		(35 "F.Fab" user "Ref Des/Assembly Top")
		(33 "B.Fab" user "Ref Des/Assembly Bottom")
	)
	(footprint ""
		(layer "B.Cu")
		(at 440.40171 -14.643354)
		(property "Reference" "C21"
			(at 0 0 0)
			(layer "B.SilkS")
			(hide yes)
			(effects
				(font
					(size 1.27 1.27)
				)
				(justify mirror)
			)
		)
		(property "Value" ""
			(at 0 0 0)
			(layer "B.Fab")
			(effects
				(font
					(size 1.27 1.27)
				)
				(justify mirror)
			)
		)
		(duplicate_pad_numbers_are_jumpers no)
		(fp_line
			(start -0.7874 -0.4064)
			(end -0.7874 0.4064)
			(stroke
				(width 0.1524)
				(type default)
			)
			(layer "B.SilkS")
		)
		(fp_line
			(start -0.7874 0.4064)
			(end 0.7874 0.4064)
			(stroke
				(width 0.1524)
				(type default)
			)
			(layer "B.SilkS")
		)
		(fp_line
			(start 0.7874 -0.4064)
			(end -0.7874 -0.4064)
			(stroke
				(width 0.1524)
				(type default)
			)
			(layer "B.SilkS")
		)
		(fp_line
			(start 0.7874 0.4064)
			(end 0.7874 -0.4064)
			(stroke
				(width 0.1524)
				(type default)
			)
			(layer "B.SilkS")
		)
		(fp_line
			(start -0.67945 -0.3048)
			(end -0.67945 0.3048)
			(stroke
				(width 0.1)
				(type default)
			)
			(layer "B.Fab")
		)
		(fp_line
			(start -0.67945 0.3048)
			(end -0.120396 0.3048)
			(stroke
				(width 0.1)
				(type default)
			)
			(layer "B.Fab")
		)
		(fp_line
			(start -0.12065 -0.3048)
			(end -0.67945 -0.3048)
			(stroke
				(width 0.1)
				(type default)
			)
			(layer "B.Fab")
		)
		(fp_line
			(start -0.12065 -0.2794)
			(end -0.12065 -0.3048)
			(stroke
				(width 0.1)
				(type default)
			)
			(layer "B.Fab")
		)
		(fp_line
			(start -0.120396 0.2794)
			(end 0.12065 0.2794)
			(stroke
				(width 0.1)
				(type default)
			)
			(layer "B.Fab")
		)
		(fp_line
			(start -0.120396 0.3048)
			(end -0.120396 0.2794)
			(stroke
				(width 0.1)
				(type default)
			)
			(layer "B.Fab")
		)
		(fp_line
			(start 0.12065 -0.305054)
			(end 0.12065 -0.2794)
			(stroke
				(width 0.1)
				(type default)
			)
			(layer "B.Fab")
		)
		(fp_line
			(start 0.12065 -0.2794)
			(end -0.12065 -0.2794)
			(stroke
				(width 0.1)
				(type default)
			)
			(layer "B.Fab")
		)
		(fp_line
			(start 0.12065 0.2794)
			(end 0.12065 0.3048)
			(stroke
				(width 0.1)
				(type default)
			)
			(layer "B.Fab")
		)
		(fp_line
			(start 0.12065 0.3048)
			(end 0.67945 0.3048)
			(stroke
				(width 0.1)
				(type default)
			)
			(layer "B.Fab")
		)
		(fp_line
			(start 0.67945 -0.305054)
			(end 0.12065 -0.305054)
			(stroke
				(width 0.1)
				(type default)
			)
			(layer "B.Fab")
		)
		(fp_line
			(start 0.67945 0.3048)
			(end 0.67945 -0.305054)
			(stroke
				(width 0.1)
				(type default)
			)
			(layer "B.Fab")
		)
		(pad "1" smd circle
			(at 0.40005 0 180)
			(size 0 0)
			(layers "B.Cu" "B.Mask" "B.Paste")
			(net "P12V_OCP_SFF_R")
		)
		(pad "2" smd circle
			(at -0.40005 0 180)
			(size 0 0)
			(layers "B.Cu" "B.Mask" "B.Paste")
			(net "GND")
		)
	)
	(footprint ""
		(layer "B.Cu")
		(at 56.073802 -194.885564 180)
		(property "Reference" "R36"
			(at 0 0 0)
			(layer "B.SilkS")
			(hide yes)
			(effects
				(font
					(size 1.27 1.27)
				)
				(justify mirror)
			)
		)
		(property "Value" ""
			(at 0 0 0)
			(layer "B.Fab")
			(effects
				(font
					(size 1.27 1.27)
				)
				(justify mirror)
			)
		)
		(duplicate_pad_numbers_are_jumpers no)
		(fp_line
			(start 0.7874 0.4064)
			(end 0.7874 -0.4064)
			(stroke
				(width 0.1524)
				(type default)
			)
			(layer "B.SilkS")
		)
		(fp_line
			(start 0.7874 -0.4064)
			(end -0.7874 -0.4064)
			(stroke
				(width 0.1524)
				(type default)
			)
			(layer "B.SilkS")
		)
		(fp_line
			(start -0.7874 0.4064)
			(end 0.7874 0.4064)
			(stroke
				(width 0.1524)
				(type default)
			)
			(layer "B.SilkS")
		)
		(fp_line
			(start -0.7874 -0.4064)
			(end -0.7874 0.4064)
			(stroke
				(width 0.1524)
				(type default)
			)
			(layer "B.SilkS")
		)
		(fp_line
			(start 0.67945 0.3048)
			(end 0.67945 -0.305054)
			(stroke
				(width 0.1)
				(type default)
			)
			(layer "B.Fab")
		)
		(fp_line
			(start 0.67945 -0.305054)
			(end 0.12065 -0.305054)
			(stroke
				(width 0.1)
				(type default)
			)
			(layer "B.Fab")
		)
		(fp_line
			(start 0.12065 0.3048)
			(end 0.67945 0.3048)
			(stroke
				(width 0.1)
				(type default)
			)
			(layer "B.Fab")
		)
		(fp_line
			(start 0.12065 0.2794)
			(end 0.12065 0.3048)
			(stroke
				(width 0.1)
				(type default)
			)
			(layer "B.Fab")
		)
		(fp_line
			(start 0.12065 -0.2794)
			(end -0.12065 -0.2794)
			(stroke
				(width 0.1)
				(type default)
			)
			(layer "B.Fab")
		)
		(fp_line
			(start 0.12065 -0.305054)
			(end 0.12065 -0.2794)
			(stroke
				(width 0.1)
				(type default)
			)
			(layer "B.Fab")
		)
		(fp_line
			(start -0.120396 0.3048)
			(end -0.120396 0.2794)
			(stroke
				(width 0.1)
				(type default)
			)
			(layer "B.Fab")
		)
		(fp_line
			(start -0.120396 0.2794)
			(end 0.12065 0.2794)
			(stroke
				(width 0.1)
				(type default)
			)
			(layer "B.Fab")
		)
		(fp_line
			(start -0.12065 -0.2794)
			(end -0.12065 -0.3048)
			(stroke
				(width 0.1)
				(type default)
			)
			(layer "B.Fab")
		)
		(fp_line
			(start -0.12065 -0.3048)
			(end -0.67945 -0.3048)
			(stroke
				(width 0.1)
				(type default)
			)
			(layer "B.Fab")
		)
		(fp_line
			(start -0.67945 0.3048)
			(end -0.120396 0.3048)
			(stroke
				(width 0.1)
				(type default)
			)
			(layer "B.Fab")
		)
		(fp_line
			(start -0.67945 -0.3048)
			(end -0.67945 0.3048)
			(stroke
				(width 0.1)
				(type default)
			)
			(layer "B.Fab")
		)
		(pad "1" smd circle
			(at 0.40005 0)
			(size 0 0)
			(layers "B.Cu" "B.Mask" "B.Paste")
			(net "PD_CHA_CPU1_DIMM0_SAA")
		)
		(pad "2" smd circle
			(at -0.40005 0)
			(size 0 0)
			(layers "B.Cu" "B.Mask" "B.Paste")
			(net "GND")
		)
	)
	(footprint ""
		(layer "B.Cu")
		(at 295.402 -427.228 180)
		(property "Reference" "R1211"
			(at 0 0 0)
			(layer "B.SilkS")
			(hide yes)
			(effects
				(font
					(size 1.27 1.27)
				)
				(justify mirror)
			)
		)
		(property "Value" ""
			(at 0 0 0)
			(layer "B.Fab")
			(effects
				(font
					(size 1.27 1.27)
				)
				(justify mirror)
			)
		)
		(duplicate_pad_numbers_are_jumpers no)
		(fp_line
			(start 0.32512 0.175006)
			(end 0.32512 -0.175006)
			(stroke
				(width 0.1)
				(type default)
			)
			(layer "B.Fab")
		)
		(fp_line
			(start 0.32512 -0.175006)
			(end -0.32512 -0.175006)
			(stroke
				(width 0.1)
				(type default)
			)
			(layer "B.Fab")
		)
		(fp_line
			(start -0.32512 0.175006)
			(end 0.32512 0.175006)
			(stroke
				(width 0.1)
				(type default)
			)
			(layer "B.Fab")
		)
		(fp_line
			(start -0.32512 -0.175006)
			(end -0.32512 0.175006)
			(stroke
				(width 0.1)
				(type default)
			)
			(layer "B.Fab")
		)
		(pad "1" smd rect
			(at 0.2667 0)
			(size 0.3048 0.381)
			(layers "B.Cu" "B.Mask" "B.Paste")
			(net "RST_SMB_RT_ROM_R1_N")
		)
		(pad "2" smd rect
			(at -0.2667 0 180)
			(size 0.3048 0.381)
			(layers "B.Cu" "B.Mask" "B.Paste")
			(net "FM_SMB_RT_ROM_MUX5_SEL")
		)
	)
)
